# BASEBOARD_FAB2 (Tioga Pass) — schematic netlist excerpt (pin names and nets, part order shuffled) for the footprints in the layout excerpt that follows; sources: Cadence DE-HDL packaged netlist, KiCad conversion of Wiwynn_Tioga_Pass_MB.brd

C5G118  CAP  47UF 4V 20% X6S  pkg 0805  page 243 : A = PVDDQ_GHJ ; B = GND

Q1L2  FET_N_DUAL  NTJD4001N FET  pkg SMLF  page 155
  SOURCE(0)  = P5V_STBY_DBG
  GATE(0)  = FM_CPLD_DBG_PWR_EN
  DRAIN(0)  = FM_CPLD_DBG_PWR_EN
  SOURCE(0)  = GND
  GATE(0)  = FM_CPLD_DBG_PWR_EN_R_N
  DRAIN(0)  = P5V_STBY

C4M5  CAP_A  47UF 4V 20% X5R  pkg 0603V  page 220 : A = PVDDQ_DEF ; B = GND

(kicad_pcb
	(version 20260206)
	(generator "pcbnew")
	(generator_version "10.0")
	(general
		(thickness 1.6)
		(legacy_teardrops no)
	)
	(paper "A4")
	(title_block
		(title "Wiwynn_Tioga_Pass_MB.brd")
		(comment 1 "Tioga Pass / footprints 4102-4104 of 4770")
	)
	(layers
		(0 "F.Cu" signal "TOP")
		(4 "In1.Cu" signal "L2GND")
		(6 "In2.Cu" signal "L3")
		(8 "In3.Cu" signal "L4GND")
		(10 "In4.Cu" signal "L5")
		(12 "In5.Cu" signal "L6GND")
		(14 "In6.Cu" signal "L7VCC")
		(16 "In7.Cu" signal "L8VCC")
		(18 "In8.Cu" signal "L9GND")
		(20 "In9.Cu" signal "L10")
		(22 "In10.Cu" signal "L11GND")
		(24 "In11.Cu" signal "L12")
		(26 "In12.Cu" signal "L13GND")
		(2 "B.Cu" signal "BOTTOM")
		(9 "F.Adhes" user "F.Adhesive")
		(11 "B.Adhes" user "B.Adhesive")
		(13 "F.Paste" user "Package Geometry/Pastemask Top")
		(15 "B.Paste" user "Package Geometry/Pastemask Bottom")
		(5 "F.SilkS" user "Ref Des/Silkscreen Top")
		(7 "B.SilkS" user "Ref Des/Silkscreen Bottom")
		(1 "F.Mask" user "Board Geometry/Soldermask Top")
		(3 "B.Mask" user "Board Geometry/Soldermask Bottom")
		(17 "Dwgs.User" user "User.Drawings")
		(19 "Cmts.User" user "User.Comments")
		(21 "Eco1.User" user "User.Eco1")
		(23 "Eco2.User" user "User.Eco2")
		(25 "Edge.Cuts" user "Board Geometry/Outline")
		(27 "Margin" user)
		(31 "F.CrtYd" user "Package Geometry/Place Bound Top")
		(29 "B.CrtYd" user "Package Geometry/Place Bound Bottom")
		(35 "F.Fab" user "Ref Des/Assembly Top")
		(33 "B.Fab" user "Ref Des/Assembly Bottom")
	)
	(footprint ""
		(layer "B.Cu")
		(at 477.29521 -150.174706)
		(property "Reference" "Q1L2"
			(at -1.8796 2.23647 0)
			(unlocked yes)
			(layer "B.SilkS")
			(effects
				(font
					(size 0.7874 0.5842)
					(thickness 0.1524)
				)
				(justify left mirror)
			)
		)
		(property "Value" ""
			(at 0 0 0)
			(layer "B.Fab")
			(effects
				(font
					(size 1.27 1.27)
				)
				(justify mirror)
			)
		)
		(duplicate_pad_numbers_are_jumpers no)
		(fp_circle
			(center 0.508 -0.7874)
			(end 0.635 -0.7874)
			(stroke
				(width 0.254)
				(type default)
			)
			(fill no)
			(layer "B.SilkS")
		)
		(fp_poly
			(pts
				(xy -0.2159 1.7526) (xy -1.5621 1.7526) (xy -1.5621 -0.4572) (xy -0.2159 -0.4572)
			)
			(stroke
				(width 0)
				(type default)
			)
			(fill no)
			(layer "B.CrtYd")
		)
		(fp_line
			(start -1.5621 -0.45466)
			(end -0.2159 -0.45466)
			(stroke
				(width 0.1)
				(type default)
			)
			(layer "B.Fab")
		)
		(fp_line
			(start -1.5621 1.75514)
			(end -1.5621 -0.45466)
			(stroke
				(width 0.1)
				(type default)
			)
			(layer "B.Fab")
		)
		(fp_line
			(start -0.2159 -0.45466)
			(end -0.2159 1.75514)
			(stroke
				(width 0.1)
				(type default)
			)
			(layer "B.Fab")
		)
		(fp_line
			(start -0.2159 1.75514)
			(end -1.5621 1.75514)
			(stroke
				(width 0.1)
				(type default)
			)
			(layer "B.Fab")
		)
		(fp_circle
			(center 0.508 -0.7874)
			(end 0.635 -0.7874)
			(stroke
				(width 0.254)
				(type default)
			)
			(fill no)
			(layer "B.Fab")
		)
		(pad "1" smd rect
			(at 0 0 180)
			(size 1.016 0.381)
			(layers "B.Cu" "B.Mask" "B.Paste")
			(net "P5V_STBY_DBG")
		)
		(pad "2" smd rect
			(at 0 0.65024 180)
			(size 1.016 0.381)
			(layers "B.Cu" "B.Mask" "B.Paste")
			(net "FM_CPLD_DBG_PWR_EN")
		)
		(pad "3" smd rect
			(at 0 1.30048 180)
			(size 1.016 0.381)
			(layers "B.Cu" "B.Mask" "B.Paste")
			(net "FM_CPLD_DBG_PWR_EN")
		)
		(pad "4" smd rect
			(at -1.778 1.30048 180)
			(size 1.016 0.381)
			(layers "B.Cu" "B.Mask" "B.Paste")
			(net "GND")
		)
		(pad "5" smd rect
			(at -1.778 0.65024 180)
			(size 1.016 0.381)
			(layers "B.Cu" "B.Mask" "B.Paste")
			(net "FM_CPLD_DBG_PWR_EN_R_N")
		)
		(pad "6" smd rect
			(at -1.778 0 180)
			(size 1.016 0.381)
			(layers "B.Cu" "B.Mask" "B.Paste")
			(net "P5V_STBY")
		)
		(zone
			(layer "B.Cu")
			(hatch none 0.5)
			(connect_pads
				(clearance 0)
			)
			(min_thickness 0.25)
			(keepout
				(tracks allowed)
				(vias not_allowed)
				(pads allowed)
				(copperpour not_allowed)
				(footprints allowed)
			)
			(placement
				(enabled no)
				(sheetname "")
			)
			(fill
				(thermal_gap 0.5)
				(thermal_bridge_width 0.5)
				(island_removal_mode 0)
			)
			(polygon
				(pts
					(xy 476.02521 -150.365206) (xy 475.00921 -150.365206) (xy 475.00921 -148.676106) (xy 476.02521 -148.676106)
				)
			)
		)
		(zone
			(layer "B.Cu")
			(hatch none 0.5)
			(connect_pads
				(clearance 0)
			)
			(min_thickness 0.25)
			(keepout
				(tracks allowed)
				(vias not_allowed)
				(pads allowed)
				(copperpour not_allowed)
				(footprints allowed)
			)
			(placement
				(enabled no)
				(sheetname "")
			)
			(fill
				(thermal_gap 0.5)
				(thermal_bridge_width 0.5)
				(island_removal_mode 0)
			)
			(polygon
				(pts
					(xy 477.80321 -150.365206) (xy 476.78721 -150.365206) (xy 476.78721 -148.676106) (xy 477.80321 -148.676106)
				)
			)
		)
	)
	(footprint ""
		(layer "B.Cu")
		(at 276.933152 -125.69444 90)
		(property "Reference" "C4M5"
			(at -1.76911 0.942848 0)
			(unlocked yes)
			(layer "B.SilkS")
			(effects
				(font
					(size 0.7874 0.5842)
					(thickness 0.1524)
				)
				(justify mirror)
			)
		)
		(property "Value" ""
			(at 0 0 90)
			(layer "B.Fab")
			(effects
				(font
					(size 1.27 1.27)
				)
				(justify mirror)
			)
		)
		(duplicate_pad_numbers_are_jumpers no)
		(fp_rect
			(start 0.500126 1.598422)
			(end -0.500126 -0.201422)
			(stroke
				(width 0)
				(type default)
			)
			(fill no)
			(layer "B.CrtYd")
		)
		(fp_line
			(start 0.500126 -0.201422)
			(end -0.500126 -0.201422)
			(stroke
				(width 0.1)
				(type default)
			)
			(layer "B.Fab")
		)
		(fp_line
			(start -0.500126 -0.201422)
			(end -0.500126 1.598422)
			(stroke
				(width 0.1)
				(type default)
			)
			(layer "B.Fab")
		)
		(fp_line
			(start 0.500126 1.598422)
			(end 0.500126 -0.201422)
			(stroke
				(width 0.1)
				(type default)
			)
			(layer "B.Fab")
		)
		(fp_line
			(start -0.500126 1.598422)
			(end 0.500126 1.598422)
			(stroke
				(width 0.1)
				(type default)
			)
			(layer "B.Fab")
		)
		(pad "1" smd rect
			(at 0 0)
			(size 0.889 0.9906)
			(layers "B.Cu" "B.Mask" "B.Paste")
			(net "PVDDQ_DEF")
		)
		(pad "2" smd rect
			(at 0 1.397)
			(size 0.889 0.9906)
			(layers "B.Cu" "B.Mask" "B.Paste")
			(net "GND")
		)
		(zone
			(layer "B.Cu")
			(hatch none 0.5)
			(connect_pads
				(clearance 0)
			)
			(min_thickness 0.25)
			(keepout
				(tracks allowed)
				(vias not_allowed)
				(pads allowed)
				(copperpour not_allowed)
				(footprints allowed)
			)
			(placement
				(enabled no)
				(sheetname "")
			)
			(fill
				(thermal_gap 0.5)
				(thermal_bridge_width 0.5)
				(island_removal_mode 0)
			)
			(polygon
				(pts
					(xy 277.885652 -126.18974) (xy 277.377652 -126.18974) (xy 277.377652 -125.19914) (xy 277.885652 -125.19914)
				)
			)
		)
		(zone
			(layer "B.Cu")
			(hatch none 0.5)
			(connect_pads
				(clearance 0)
			)
			(min_thickness 0.25)
			(keepout
				(tracks not_allowed)
				(vias allowed)
				(pads allowed)
				(copperpour not_allowed)
				(footprints allowed)
			)
			(placement
				(enabled no)
				(sheetname "")
			)
			(fill
				(thermal_gap 0.5)
				(thermal_bridge_width 0.5)
				(island_removal_mode 0)
			)
			(polygon
				(pts
					(xy 277.885652 -126.18974) (xy 277.377652 -126.18974) (xy 277.377652 -125.19914) (xy 277.885652 -125.19914)
				)
			)
		)
	)
	(footprint ""
		(layer "B.Cu")
		(at 94.313248 -12.999212 90)
		(property "Reference" "C5G118"
			(at -1.64973 0.78994 180)
			(unlocked yes)
			(layer "B.SilkS")
			(effects
				(font
					(size 0.7874 0.5842)
					(thickness 0.1524)
				)
				(justify mirror)
			)
		)
		(property "Value" ""
			(at 0 0 90)
			(layer "B.Fab")
			(effects
				(font
					(size 1.27 1.27)
				)
				(justify mirror)
			)
		)
		(duplicate_pad_numbers_are_jumpers no)
		(fp_rect
			(start -0.7239 -0.2159)
			(end 0.7239 1.9939)
			(stroke
				(width 0)
				(type default)
			)
			(fill no)
			(layer "B.CrtYd")
		)
		(fp_line
			(start 0.7239 -0.2159)
			(end 0.7239 1.9939)
			(stroke
				(width 0.1)
				(type default)
			)
			(layer "B.Fab")
		)
		(fp_line
			(start -0.7239 -0.2159)
			(end 0.7239 -0.2159)
			(stroke
				(width 0.1)
				(type default)
			)
			(layer "B.Fab")
		)
		(fp_line
			(start 0.7239 1.9939)
			(end -0.7239 1.9939)
			(stroke
				(width 0.1)
				(type default)
			)
			(layer "B.Fab")
		)
		(fp_line
			(start -0.7239 1.9939)
			(end -0.7239 -0.2159)
			(stroke
				(width 0.1)
				(type default)
			)
			(layer "B.Fab")
		)
		(pad "1" smd rect
			(at 0 0 270)
			(size 1.27 1.016)
			(layers "B.Cu" "B.Mask" "B.Paste")
			(net "PVDDQ_GHJ")
		)
		(pad "2" smd rect
			(at 0 1.778 270)
			(size 1.27 1.016)
			(layers "B.Cu" "B.Mask" "B.Paste")
			(net "GND")
		)
		(zone
			(layer "B.Cu")
			(hatch none 0.5)
			(connect_pads
				(clearance 0)
			)
			(min_thickness 0.25)
			(keepout
				(tracks not_allowed)
				(vias allowed)
				(pads allowed)
				(copperpour not_allowed)
				(footprints allowed)
			)
			(placement
				(enabled no)
				(sheetname "")
			)
			(fill
				(thermal_gap 0.5)
				(thermal_bridge_width 0.5)
				(island_removal_mode 0)
			)
			(polygon
				(pts
					(xy 94.821248 -12.364212) (xy 95.583248 -12.364212) (xy 95.583248 -13.634212) (xy 94.821248 -13.634212)
				)
			)
		)
	)
)
